# S9S_MB_2U (Grand Teton) — schematic netlist excerpt (pin names and nets, part order shuffled) for the footprints in the layout excerpt that follows; sources: Cadence DE-HDL packaged netlist, KiCad conversion of 03242023_DA0F0TMBIJ0_F0T_Motherboard_J_brd_V01_OCP.brd

C852  Q_CAP_DIFFBUS  DIFF BUS_0.22UF 6.3V 20% X6S  pkg C0201  page 174 : \1\ = P5E_CPU0_PE1_TX_C_DN<8> ; \2\ = P5E_CPU0_PE1_TX_DN<8>
R4152  Q_RES  33.2 1% CHIP  pkg 0402LF  page 241 : A = SMB_1_PLD_3V3AUX_SDA ; B = SMB_2_PLD_3V3AUX_SDA_R1
PR1772  Q_RES  3.3 1% CHIP  pkg 0402LF  page 270 : A = SW_PVCCIN_CPU0_BOOT8 ; B = SW_PVCCIN_CPU0_BOOT8_R

(kicad_pcb
	(version 20260206)
	(generator "pcbnew")
	(generator_version "10.0")
	(general
		(thickness 1.6)
		(legacy_teardrops no)
	)
	(paper "A4")
	(title_block
		(title "03242023_DA0F0TMBIJ0_F0T_Motherboard_J_brd_V01_OCP.brd")
		(comment 1 "Grand Teton / footprints 1896-1898 of 6105")
	)
	(layers
		(0 "F.Cu" signal "TOP")
		(4 "In1.Cu" signal "GND")
		(6 "In2.Cu" signal "IN1")
		(8 "In3.Cu" signal "GND1")
		(10 "In4.Cu" signal "IN2")
		(12 "In5.Cu" signal "GND2")
		(14 "In6.Cu" signal "IN3")
		(16 "In7.Cu" signal "GND3")
		(18 "In8.Cu" signal "VCC")
		(20 "In9.Cu" signal "VCC1")
		(22 "In10.Cu" signal "GND4")
		(24 "In11.Cu" signal "IN4")
		(26 "In12.Cu" signal "GND5")
		(28 "In13.Cu" signal "IN5")
		(30 "In14.Cu" signal "GND6")
		(32 "In15.Cu" signal "IN6")
		(34 "In16.Cu" signal "GND7")
		(2 "B.Cu" signal "BOTTOM")
		(9 "F.Adhes" user "F.Adhesive")
		(11 "B.Adhes" user "B.Adhesive")
		(13 "F.Paste" user "Package Geometry/Pastemask Top")
		(15 "B.Paste" user "Package Geometry/Pastemask Bottom")
		(5 "F.SilkS" user "Ref Des/Silkscreen Top")
		(7 "B.SilkS" user "Ref Des/Silkscreen Bottom")
		(1 "F.Mask" user "Board Geometry/Soldermask Top")
		(3 "B.Mask" user "Board Geometry/Soldermask Bottom")
		(17 "Dwgs.User" user "User.Drawings")
		(19 "Cmts.User" user "User.Comments")
		(21 "Eco1.User" user "User.Eco1")
		(23 "Eco2.User" user "User.Eco2")
		(25 "Edge.Cuts" user "Board Geometry/Outline")
		(27 "Margin" user)
		(31 "F.CrtYd" user "Package Geometry/Place Bound Top")
		(29 "B.CrtYd" user "Package Geometry/Place Bound Bottom")
		(35 "F.Fab" user "Ref Des/Assembly Top")
		(33 "B.Fab" user "Ref Des/Assembly Bottom")
	)
	(footprint ""
		(layer "F.Cu")
		(at 160.760918 -22.361906 180)
		(property "Reference" "R4152"
			(at 0 0 180)
			(layer "F.SilkS")
			(hide yes)
			(effects
				(font
					(size 1.27 1.27)
				)
			)
		)
		(property "Value" ""
			(at 0 0 180)
			(layer "F.Fab")
			(effects
				(font
					(size 1.27 1.27)
				)
			)
		)
		(duplicate_pad_numbers_are_jumpers no)
		(fp_line
			(start 0.7874 0.4064)
			(end -0.7874 0.4064)
			(stroke
				(width 0.1524)
				(type default)
			)
			(layer "F.SilkS")
		)
		(fp_line
			(start 0.7874 -0.4064)
			(end 0.7874 0.4064)
			(stroke
				(width 0.1524)
				(type default)
			)
			(layer "F.SilkS")
		)
		(fp_line
			(start -0.7874 0.4064)
			(end -0.7874 -0.4064)
			(stroke
				(width 0.1524)
				(type default)
			)
			(layer "F.SilkS")
		)
		(fp_line
			(start -0.7874 -0.4064)
			(end 0.7874 -0.4064)
			(stroke
				(width 0.1524)
				(type default)
			)
			(layer "F.SilkS")
		)
		(fp_line
			(start 0.67945 0.3048)
			(end 0.120396 0.3048)
			(stroke
				(width 0.1)
				(type default)
			)
			(layer "F.Fab")
		)
		(fp_line
			(start 0.67945 -0.3048)
			(end 0.67945 0.3048)
			(stroke
				(width 0.1)
				(type default)
			)
			(layer "F.Fab")
		)
		(fp_line
			(start 0.12065 -0.2794)
			(end 0.12065 -0.3048)
			(stroke
				(width 0.1)
				(type default)
			)
			(layer "F.Fab")
		)
		(fp_line
			(start 0.12065 -0.3048)
			(end 0.67945 -0.3048)
			(stroke
				(width 0.1)
				(type default)
			)
			(layer "F.Fab")
		)
		(fp_line
			(start 0.120396 0.3048)
			(end 0.120396 0.2794)
			(stroke
				(width 0.1)
				(type default)
			)
			(layer "F.Fab")
		)
		(fp_line
			(start 0.120396 0.2794)
			(end -0.12065 0.2794)
			(stroke
				(width 0.1)
				(type default)
			)
			(layer "F.Fab")
		)
		(fp_line
			(start -0.12065 0.3048)
			(end -0.67945 0.3048)
			(stroke
				(width 0.1)
				(type default)
			)
			(layer "F.Fab")
		)
		(fp_line
			(start -0.12065 0.2794)
			(end -0.12065 0.3048)
			(stroke
				(width 0.1)
				(type default)
			)
			(layer "F.Fab")
		)
		(fp_line
			(start -0.12065 -0.2794)
			(end 0.12065 -0.2794)
			(stroke
				(width 0.1)
				(type default)
			)
			(layer "F.Fab")
		)
		(fp_line
			(start -0.12065 -0.305054)
			(end -0.12065 -0.2794)
			(stroke
				(width 0.1)
				(type default)
			)
			(layer "F.Fab")
		)
		(fp_line
			(start -0.67945 0.3048)
			(end -0.67945 -0.305054)
			(stroke
				(width 0.1)
				(type default)
			)
			(layer "F.Fab")
		)
		(fp_line
			(start -0.67945 -0.305054)
			(end -0.12065 -0.305054)
			(stroke
				(width 0.1)
				(type default)
			)
			(layer "F.Fab")
		)
		(pad "1" smd circle
			(at -0.40005 0 180)
			(size 0 0)
			(layers "F.Cu" "F.Mask" "F.Paste")
			(net "SMB_1_PLD_3V3AUX_SDA")
		)
		(pad "2" smd circle
			(at 0.40005 0 180)
			(size 0 0)
			(layers "F.Cu" "F.Mask" "F.Paste")
			(net "SMB_2_PLD_3V3AUX_SDA_R1")
		)
	)
	(footprint ""
		(layer "F.Cu")
		(at 386.499354 -347.520514 90)
		(property "Reference" "PR1772"
			(at 0 0 90)
			(layer "F.SilkS")
			(hide yes)
			(effects
				(font
					(size 1.27 1.27)
				)
			)
		)
		(property "Value" ""
			(at 0 0 90)
			(layer "F.Fab")
			(effects
				(font
					(size 1.27 1.27)
				)
			)
		)
		(duplicate_pad_numbers_are_jumpers no)
		(fp_line
			(start 0.7874 -0.4064)
			(end 0.7874 0.4064)
			(stroke
				(width 0.1524)
				(type default)
			)
			(layer "F.SilkS")
		)
		(fp_line
			(start -0.7874 -0.4064)
			(end 0.7874 -0.4064)
			(stroke
				(width 0.1524)
				(type default)
			)
			(layer "F.SilkS")
		)
		(fp_line
			(start 0.7874 0.4064)
			(end -0.7874 0.4064)
			(stroke
				(width 0.1524)
				(type default)
			)
			(layer "F.SilkS")
		)
		(fp_line
			(start -0.7874 0.4064)
			(end -0.7874 -0.4064)
			(stroke
				(width 0.1524)
				(type default)
			)
			(layer "F.SilkS")
		)
		(fp_line
			(start -0.12065 -0.305054)
			(end -0.12065 -0.2794)
			(stroke
				(width 0.1)
				(type default)
			)
			(layer "F.Fab")
		)
		(fp_line
			(start -0.67945 -0.305054)
			(end -0.12065 -0.305054)
			(stroke
				(width 0.1)
				(type default)
			)
			(layer "F.Fab")
		)
		(fp_line
			(start 0.67945 -0.3048)
			(end 0.67945 0.3048)
			(stroke
				(width 0.1)
				(type default)
			)
			(layer "F.Fab")
		)
		(fp_line
			(start 0.12065 -0.3048)
			(end 0.67945 -0.3048)
			(stroke
				(width 0.1)
				(type default)
			)
			(layer "F.Fab")
		)
		(fp_line
			(start 0.12065 -0.2794)
			(end 0.12065 -0.3048)
			(stroke
				(width 0.1)
				(type default)
			)
			(layer "F.Fab")
		)
		(fp_line
			(start -0.12065 -0.2794)
			(end 0.12065 -0.2794)
			(stroke
				(width 0.1)
				(type default)
			)
			(layer "F.Fab")
		)
		(fp_line
			(start 0.120396 0.2794)
			(end -0.12065 0.2794)
			(stroke
				(width 0.1)
				(type default)
			)
			(layer "F.Fab")
		)
		(fp_line
			(start -0.12065 0.2794)
			(end -0.12065 0.3048)
			(stroke
				(width 0.1)
				(type default)
			)
			(layer "F.Fab")
		)
		(fp_line
			(start 0.67945 0.3048)
			(end 0.120396 0.3048)
			(stroke
				(width 0.1)
				(type default)
			)
			(layer "F.Fab")
		)
		(fp_line
			(start 0.120396 0.3048)
			(end 0.120396 0.2794)
			(stroke
				(width 0.1)
				(type default)
			)
			(layer "F.Fab")
		)
		(fp_line
			(start -0.12065 0.3048)
			(end -0.67945 0.3048)
			(stroke
				(width 0.1)
				(type default)
			)
			(layer "F.Fab")
		)
		(fp_line
			(start -0.67945 0.3048)
			(end -0.67945 -0.305054)
			(stroke
				(width 0.1)
				(type default)
			)
			(layer "F.Fab")
		)
		(pad "1" smd circle
			(at -0.40005 0 90)
			(size 0 0)
			(layers "F.Cu" "F.Mask" "F.Paste")
			(net "SW_PVCCIN_CPU0_BOOT8")
		)
		(pad "2" smd circle
			(at 0.40005 0 90)
			(size 0 0)
			(layers "F.Cu" "F.Mask" "F.Paste")
			(net "SW_PVCCIN_CPU0_BOOT8_R")
		)
	)
	(footprint ""
		(layer "F.Cu")
		(at 409.573984 -17.612614 90)
		(property "Reference" "C852"
			(at 0 0 90)
			(layer "F.SilkS")
			(hide yes)
			(effects
				(font
					(size 1.27 1.27)
				)
			)
		)
		(property "Value" ""
			(at 0 0 90)
			(layer "F.Fab")
			(effects
				(font
					(size 1.27 1.27)
				)
			)
		)
		(duplicate_pad_numbers_are_jumpers no)
		(fp_line
			(start 0.299974 -0.150114)
			(end 0.299974 0.150114)
			(stroke
				(width 0.1)
				(type default)
			)
			(layer "F.Fab")
		)
		(fp_line
			(start -0.299974 -0.150114)
			(end 0.299974 -0.150114)
			(stroke
				(width 0.1)
				(type default)
			)
			(layer "F.Fab")
		)
		(fp_line
			(start 0.299974 0.150114)
			(end -0.299974 0.150114)
			(stroke
				(width 0.1)
				(type default)
			)
			(layer "F.Fab")
		)
		(fp_line
			(start -0.299974 0.150114)
			(end -0.299974 -0.150114)
			(stroke
				(width 0.1)
				(type default)
			)
			(layer "F.Fab")
		)
		(pad "1" smd rect
			(at -0.2667 0 90)
			(size 0.3048 0.381)
			(layers "F.Cu" "F.Mask" "F.Paste")
			(net "P5E_CPU0_PE1_TX_C_DN<8>")
		)
		(pad "2" smd rect
			(at 0.2667 0 90)
			(size 0.3048 0.381)
			(layers "F.Cu" "F.Mask" "F.Paste")
			(net "P5E_CPU0_PE1_TX_DN<8>")
		)
	)
)
